(kicad_pcb
	(version 20260206)
	(generator "pcbnew")
	(generator_version "10.0")
	(general
		(thickness 1.6)
		(legacy_teardrops no)
	)
	(paper "A4")
	(title_block
		(title "03242023_DA0F0TMBIJ0_F0T_Motherboard_J_brd_V01_OCP.brd")
		(comment 1 "Grand Teton / footprints 660-662 of 6105")
	)
	(layers
		(0 "F.Cu" signal "TOP")
		(4 "In1.Cu" signal "GND")
		(6 "In2.Cu" signal "IN1")
		(8 "In3.Cu" signal "GND1")
		(10 "In4.Cu" signal "IN2")
		(12 "In5.Cu" signal "GND2")
		(14 "In6.Cu" signal "IN3")
		(16 "In7.Cu" signal "GND3")
		(18 "In8.Cu" signal "VCC")
		(20 "In9.Cu" signal "VCC1")
		(22 "In10.Cu" signal "GND4")
		(24 "In11.Cu" signal "IN4")
		(26 "In12.Cu" signal "GND5")
		(28 "In13.Cu" signal "IN5")
		(30 "In14.Cu" signal "GND6")
		(32 "In15.Cu" signal "IN6")
		(34 "In16.Cu" signal "GND7")
		(2 "B.Cu" signal "BOTTOM")
		(9 "F.Adhes" user "F.Adhesive")
		(11 "B.Adhes" user "B.Adhesive")
		(13 "F.Paste" user "Package Geometry/Pastemask Top")
		(15 "B.Paste" user "Package Geometry/Pastemask Bottom")
		(5 "F.SilkS" user "Ref Des/Silkscreen Top")
		(7 "B.SilkS" user "Ref Des/Silkscreen Bottom")
		(1 "F.Mask" user "Board Geometry/Soldermask Top")
		(3 "B.Mask" user "Board Geometry/Soldermask Bottom")
		(17 "Dwgs.User" user "User.Drawings")
		(19 "Cmts.User" user "User.Comments")
		(21 "Eco1.User" user "User.Eco1")
		(23 "Eco2.User" user "User.Eco2")
		(25 "Edge.Cuts" user "Board Geometry/Outline")
		(27 "Margin" user)
		(31 "F.CrtYd" user "Package Geometry/Place Bound Top")
		(29 "B.CrtYd" user "Package Geometry/Place Bound Bottom")
		(35 "F.Fab" user "Ref Des/Assembly Top")
		(33 "B.Fab" user "Ref Des/Assembly Bottom")
	)
	(footprint ""
		(layer "F.Cu")
		(at 284.599888 -411.29204 -90)
		(property "Reference" "C2342"
			(at 0 0 270)
			(layer "F.SilkS")
			(hide yes)
			(effects
				(font
					(size 1.27 1.27)
				)
			)
		)
		(property "Value" ""
			(at 0 0 270)
			(layer "F.Fab")
			(effects
				(font
					(size 1.27 1.27)
				)
			)
		)
		(duplicate_pad_numbers_are_jumpers no)
		(fp_line
			(start -0.7874 0.4064)
			(end -0.7874 -0.4064)
			(stroke
				(width 0.1524)
				(type default)
			)
			(layer "F.SilkS")
		)
		(fp_line
			(start 0.7874 0.4064)
			(end -0.7874 0.4064)
			(stroke
				(width 0.1524)
				(type default)
			)
			(layer "F.SilkS")
		)
		(fp_line
			(start -0.7874 -0.4064)
			(end 0.7874 -0.4064)
			(stroke
				(width 0.1524)
				(type default)
			)
			(layer "F.SilkS")
		)
		(fp_line
			(start 0.7874 -0.4064)
			(end 0.7874 0.4064)
			(stroke
				(width 0.1524)
				(type default)
			)
			(layer "F.SilkS")
		)
		(fp_line
			(start -0.67945 0.3048)
			(end -0.67945 -0.305054)
			(stroke
				(width 0.1)
				(type default)
			)
			(layer "F.Fab")
		)
		(fp_line
			(start -0.12065 0.3048)
			(end -0.67945 0.3048)
			(stroke
				(width 0.1)
				(type default)
			)
			(layer "F.Fab")
		)
		(fp_line
			(start 0.120396 0.3048)
			(end 0.120396 0.2794)
			(stroke
				(width 0.1)
				(type default)
			)
			(layer "F.Fab")
		)
		(fp_line
			(start 0.67945 0.3048)
			(end 0.120396 0.3048)
			(stroke
				(width 0.1)
				(type default)
			)
			(layer "F.Fab")
		)
		(fp_line
			(start -0.12065 0.2794)
			(end -0.12065 0.3048)
			(stroke
				(width 0.1)
				(type default)
			)
			(layer "F.Fab")
		)
		(fp_line
			(start 0.120396 0.2794)
			(end -0.12065 0.2794)
			(stroke
				(width 0.1)
				(type default)
			)
			(layer "F.Fab")
		)
		(fp_line
			(start -0.12065 -0.2794)
			(end 0.12065 -0.2794)
			(stroke
				(width 0.1)
				(type default)
			)
			(layer "F.Fab")
		)
		(fp_line
			(start 0.12065 -0.2794)
			(end 0.12065 -0.3048)
			(stroke
				(width 0.1)
				(type default)
			)
			(layer "F.Fab")
		)
		(fp_line
			(start 0.12065 -0.3048)
			(end 0.67945 -0.3048)
			(stroke
				(width 0.1)
				(type default)
			)
			(layer "F.Fab")
		)
		(fp_line
			(start 0.67945 -0.3048)
			(end 0.67945 0.3048)
			(stroke
				(width 0.1)
				(type default)
			)
			(layer "F.Fab")
		)
		(fp_line
			(start -0.67945 -0.305054)
			(end -0.12065 -0.305054)
			(stroke
				(width 0.1)
				(type default)
			)
			(layer "F.Fab")
		)
		(fp_line
			(start -0.12065 -0.305054)
			(end -0.12065 -0.2794)
			(stroke
				(width 0.1)
				(type default)
			)
			(layer "F.Fab")
		)
		(pad "1" smd circle
			(at -0.40005 0 270)
			(size 0 0)
			(layers "F.Cu" "F.Mask" "F.Paste")
			(net "HPDB_HSC_PWRGD_ISO")
		)
		(pad "2" smd circle
			(at 0.40005 0 270)
			(size 0 0)
			(layers "F.Cu" "F.Mask" "F.Paste")
			(net "GND")
		)
	)
	(footprint ""
		(layer "F.Cu")
		(at 353.0727 -324.445376)
		(property "Reference" "PL13"
			(at -12.45616 6.763258 0)
			(unlocked yes)
			(layer "F.SilkS")
			(effects
				(font
					(size 0.7874 0.5842)
					(thickness 0.1524)
				)
				(justify left)
			)
		)
		(property "Value" ""
			(at 0 0 0)
			(layer "F.Fab")
			(effects
				(font
					(size 1.27 1.27)
				)
			)
		)
		(duplicate_pad_numbers_are_jumpers no)
		(fp_line
			(start -3.750056 -5.500116)
			(end -2.393442 -5.500116)
			(stroke
				(width 0.1524)
				(type default)
			)
			(layer "F.SilkS")
		)
		(fp_line
			(start -3.750056 5.500116)
			(end -3.750056 -5.500116)
			(stroke
				(width 0.1524)
				(type default)
			)
			(layer "F.SilkS")
		)
		(fp_line
			(start -2.393442 5.500116)
			(end -3.750056 5.500116)
			(stroke
				(width 0.1524)
				(type default)
			)
			(layer "F.SilkS")
		)
		(fp_line
			(start 2.393442 5.500116)
			(end 3.750056 5.500116)
			(stroke
				(width 0.1524)
				(type default)
			)
			(layer "F.SilkS")
		)
		(fp_line
			(start 3.750056 -5.500116)
			(end 2.393442 -5.500116)
			(stroke
				(width 0.1524)
				(type default)
			)
			(layer "F.SilkS")
		)
		(fp_line
			(start 3.750056 -4.449572)
			(end 3.750056 -5.500116)
			(stroke
				(width 0.1524)
				(type default)
			)
			(layer "F.SilkS")
		)
		(fp_line
			(start 3.750056 5.500116)
			(end 3.750056 -3.560572)
			(stroke
				(width 0.1524)
				(type default)
			)
			(layer "F.SilkS")
		)
		(fp_poly
			(pts
				(xy -3.434334 -7.043674) (xy -3.074924 -5.965952) (xy -4.152646 -6.325108)
			)
			(stroke
				(width 0)
				(type default)
			)
			(fill yes)
			(layer "F.SilkS")
		)
		(fp_line
			(start -3.750056 -5.500116)
			(end -3.750056 5.500116)
			(stroke
				(width 0.1)
				(type default)
			)
			(layer "F.Fab")
		)
		(fp_line
			(start -3.750056 5.500116)
			(end 3.750056 5.500116)
			(stroke
				(width 0.1)
				(type default)
			)
			(layer "F.Fab")
		)
		(fp_line
			(start 3.750056 -5.500116)
			(end -3.750056 -5.500116)
			(stroke
				(width 0.1)
				(type default)
			)
			(layer "F.Fab")
		)
		(fp_line
			(start 3.750056 5.500116)
			(end 3.750056 -5.500116)
			(stroke
				(width 0.1)
				(type default)
			)
			(layer "F.Fab")
		)
		(fp_poly
			(pts
				(xy -4.9276 -4.757928) (xy -4.9276 -3.741928) (xy -3.9116 -4.249928)
			)
			(stroke
				(width 0)
				(type default)
			)
			(fill yes)
			(layer "F.Fab")
		)
		(pad "1" smd rect
			(at 0 -4.249928 270)
			(size 2.413 4.5212)
			(layers "F.Cu" "F.Mask" "F.Paste")
			(net "SW_PVCCIN_CPU0_SW2")
		)
		(pad "2" smd rect
			(at 0 -1.175004 270)
			(size 1.3716 4.5212)
			(layers "F.Cu" "F.Mask" "F.Paste")
			(net "IND_P0_CPL2")
		)
		(pad "3" smd rect
			(at 0 1.175004 270)
			(size 1.3716 4.5212)
			(layers "F.Cu" "F.Mask" "F.Paste")
			(net "IND_P0_CPL3")
		)
		(pad "4" smd rect
			(at 0 4.249928 270)
			(size 2.413 4.5212)
			(layers "F.Cu" "F.Mask" "F.Paste")
			(net "PVCCIN_CPU0")
		)
	)
	(footprint ""
		(layer "F.Cu")
		(at 466.24748 -53.449728)
		(property "Reference" ""
			(at 0 0 0)
			(layer "F.SilkS")
			(hide yes)
			(effects
				(font
					(size 1.27 1.27)
				)
			)
		)
		(property "Value" ""
			(at 0 0 0)
			(layer "F.Fab")
			(effects
				(font
					(size 1.27 1.27)
				)
			)
		)
		(duplicate_pad_numbers_are_jumpers no)
		(pad "1" smd circle
			(at 0 0)
			(size 0.9906 0.9906)
			(layers "F.Cu" "F.Mask" "F.Paste")
			(net "Net_295")
		)
		(zone
			(layer "F.Cu")
			(hatch none 0.5)
			(connect_pads
				(clearance 0)
			)
			(min_thickness 0.25)
			(keepout
				(tracks not_allowed)
				(vias allowed)
				(pads allowed)
				(copperpour not_allowed)
				(footprints allowed)
			)
			(placement
				(enabled no)
				(sheetname "")
			)
			(fill
				(thermal_gap 0.5)
				(thermal_bridge_width 0.5)
				(island_removal_mode 0)
			)
			(polygon
				(pts
					(arc
						(start 467.87308 -53.449728)
						(mid 464.62188 -53.449728)
						(end 467.87308 -53.449728)
					)
				)
			)
		)
	)
)
